# BASEBOARD_FAB2 (Tioga Pass) — schematic netlist excerpt (pin names and nets, part order shuffled) for the footprints in the layout excerpt that follows; sources: Cadence DE-HDL packaged netlist, KiCad conversion of Wiwynn_Tioga_Pass_MB.brd

R30W1  RES  0.0 5% CHIP  pkg 0402  page 253 : A = USB3_P01_RXN ; B = USB3_P01_FB_RXN
C3N6  CAP_A  1.0UF 6.3V 10% X6S  pkg 0402V  page 132 : A = PVNN_PCH_STBY ; B = GND

(kicad_pcb
	(version 20260206)
	(generator "pcbnew")
	(generator_version "10.0")
	(general
		(thickness 1.6)
		(legacy_teardrops no)
	)
	(paper "A4")
	(title_block
		(title "Wiwynn_Tioga_Pass_MB.brd")
		(comment 1 "Tioga Pass / footprints 2623-2624 of 4770")
	)
	(layers
		(0 "F.Cu" signal "TOP")
		(4 "In1.Cu" signal "L2GND")
		(6 "In2.Cu" signal "L3")
		(8 "In3.Cu" signal "L4GND")
		(10 "In4.Cu" signal "L5")
		(12 "In5.Cu" signal "L6GND")
		(14 "In6.Cu" signal "L7VCC")
		(16 "In7.Cu" signal "L8VCC")
		(18 "In8.Cu" signal "L9GND")
		(20 "In9.Cu" signal "L10")
		(22 "In10.Cu" signal "L11GND")
		(24 "In11.Cu" signal "L12")
		(26 "In12.Cu" signal "L13GND")
		(2 "B.Cu" signal "BOTTOM")
		(9 "F.Adhes" user "F.Adhesive")
		(11 "B.Adhes" user "B.Adhesive")
		(13 "F.Paste" user "Package Geometry/Pastemask Top")
		(15 "B.Paste" user "Package Geometry/Pastemask Bottom")
		(5 "F.SilkS" user "Ref Des/Silkscreen Top")
		(7 "B.SilkS" user "Ref Des/Silkscreen Bottom")
		(1 "F.Mask" user "Board Geometry/Soldermask Top")
		(3 "B.Mask" user "Board Geometry/Soldermask Bottom")
		(17 "Dwgs.User" user "User.Drawings")
		(19 "Cmts.User" user "User.Comments")
		(21 "Eco1.User" user "User.Eco1")
		(23 "Eco2.User" user "User.Eco2")
		(25 "Edge.Cuts" user "Board Geometry/Outline")
		(27 "Margin" user)
		(31 "F.CrtYd" user "Package Geometry/Place Bound Top")
		(29 "B.CrtYd" user "Package Geometry/Place Bound Bottom")
		(35 "F.Fab" user "Ref Des/Assembly Top")
		(33 "B.Fab" user "Ref Des/Assembly Bottom")
	)
	(footprint ""
		(layer "B.Cu")
		(at 486.114344 -58.908696 90)
		(property "Reference" "R30W1"
			(at 0.8382 -0.67818 90)
			(unlocked yes)
			(layer "B.SilkS")
			(effects
				(font
					(size 0.4064 0.254)
					(thickness 0.1524)
				)
				(justify left mirror)
			)
		)
		(property "Value" ""
			(at 0 0 90)
			(layer "B.Fab")
			(effects
				(font
					(size 1.27 1.27)
				)
				(justify mirror)
			)
		)
		(duplicate_pad_numbers_are_jumpers no)
		(fp_poly
			(pts
				(xy 0.2794 -0.1016) (xy -0.2794 -0.1016) (xy -0.2794 0.9906) (xy 0.2794 0.9906)
			)
			(stroke
				(width 0)
				(type default)
			)
			(fill no)
			(layer "B.CrtYd")
		)
		(fp_line
			(start 0.2794 -0.1016)
			(end 0.2794 0.9906)
			(stroke
				(width 0.1)
				(type default)
			)
			(layer "B.Fab")
		)
		(fp_line
			(start -0.2794 -0.1016)
			(end 0.2794 -0.1016)
			(stroke
				(width 0.1)
				(type default)
			)
			(layer "B.Fab")
		)
		(fp_line
			(start 0.2794 0.9906)
			(end -0.2794 0.9906)
			(stroke
				(width 0.1)
				(type default)
			)
			(layer "B.Fab")
		)
		(fp_line
			(start -0.2794 0.9906)
			(end -0.2794 -0.1016)
			(stroke
				(width 0.1)
				(type default)
			)
			(layer "B.Fab")
		)
		(pad "1" smd rect
			(at 0 0 270)
			(size 0.508 0.508)
			(layers "B.Cu" "B.Mask" "B.Paste")
			(net "USB3_P01_RXN")
		)
		(pad "2" smd rect
			(at 0 0.889 270)
			(size 0.508 0.508)
			(layers "B.Cu" "B.Mask" "B.Paste")
			(net "USB3_P01_FB_RXN")
		)
		(zone
			(layer "B.Cu")
			(hatch none 0.5)
			(connect_pads
				(clearance 0)
			)
			(min_thickness 0.25)
			(keepout
				(tracks allowed)
				(vias not_allowed)
				(pads allowed)
				(copperpour not_allowed)
				(footprints allowed)
			)
			(placement
				(enabled no)
				(sheetname "")
			)
			(fill
				(thermal_gap 0.5)
				(thermal_bridge_width 0.5)
				(island_removal_mode 0)
			)
			(polygon
				(pts
					(xy 486.368344 -59.162696) (xy 486.368344 -58.654696) (xy 486.749344 -58.654696) (xy 486.749344 -59.162696)
				)
			)
		)
		(zone
			(layer "B.Cu")
			(hatch none 0.5)
			(connect_pads
				(clearance 0)
			)
			(min_thickness 0.25)
			(keepout
				(tracks not_allowed)
				(vias allowed)
				(pads allowed)
				(copperpour not_allowed)
				(footprints allowed)
			)
			(placement
				(enabled no)
				(sheetname "")
			)
			(fill
				(thermal_gap 0.5)
				(thermal_bridge_width 0.5)
				(island_removal_mode 0)
			)
			(polygon
				(pts
					(xy 486.749344 -59.162696) (xy 486.749344 -58.654696) (xy 486.368344 -58.654696) (xy 486.368344 -59.162696)
				)
			)
		)
	)
	(footprint ""
		(layer "B.Cu")
		(at 386.13715 -111.05515 180)
		(property "Reference" "C3N6"
			(at 0 0 0)
			(layer "B.SilkS")
			(hide yes)
			(effects
				(font
					(size 1.27 1.27)
				)
				(justify mirror)
			)
		)
		(property "Value" ""
			(at 0 0 0)
			(layer "B.Fab")
			(effects
				(font
					(size 1.27 1.27)
				)
				(justify mirror)
			)
		)
		(duplicate_pad_numbers_are_jumpers no)
		(fp_rect
			(start 0.2794 0.9144)
			(end -0.2794 -0.1143)
			(stroke
				(width 0)
				(type default)
			)
			(fill no)
			(layer "B.CrtYd")
		)
		(fp_line
			(start 0.2794 0.9144)
			(end 0.2794 -0.1143)
			(stroke
				(width 0.1)
				(type default)
			)
			(layer "B.Fab")
		)
		(fp_line
			(start 0.2794 -0.1143)
			(end -0.2794 -0.1143)
			(stroke
				(width 0.1)
				(type default)
			)
			(layer "B.Fab")
		)
		(fp_line
			(start -0.2794 0.9144)
			(end 0.2794 0.9144)
			(stroke
				(width 0.1)
				(type default)
			)
			(layer "B.Fab")
		)
		(fp_line
			(start -0.2794 -0.1143)
			(end -0.2794 0.9144)
			(stroke
				(width 0.1)
				(type default)
			)
			(layer "B.Fab")
		)
		(pad "1" smd custom
			(at 0 0 90)
			(size 0.10414 0.10414)
			(layers "B.Cu" "B.Mask" "B.Paste")
			(net "PVNN_PCH_STBY")
			(options
				(clearance outline)
				(anchor circle)
			)
			(primitives
				(gr_poly
					(pts
						(xy -0.20828 -0.08636) (xy -0.20828 0.08636) (xy -0.08636 0.20828) (xy 0.086614 0.20828) (xy 0.20828 0.086614)
						(xy 0.20828 -0.08636) (xy 0.08636 -0.20828) (xy -0.08636 -0.20828)
					)
					(width 0)
					(fill yes)
				)
			)
		)
		(pad "2" smd custom
			(at 0 0.8001 90)
			(size 0.10414 0.10414)
			(layers "B.Cu" "B.Mask" "B.Paste")
			(net "GND")
			(options
				(clearance outline)
				(anchor circle)
			)
			(primitives
				(gr_poly
					(pts
						(xy -0.20828 -0.08636) (xy -0.20828 0.08636) (xy -0.08636 0.20828) (xy 0.086614 0.20828) (xy 0.20828 0.086614)
						(xy 0.20828 -0.08636) (xy 0.08636 -0.20828) (xy -0.08636 -0.20828)
					)
					(width 0)
					(fill yes)
				)
			)
		)
		(zone
			(layer "B.Cu")
			(hatch none 0.5)
			(connect_pads
				(clearance 0)
			)
			(min_thickness 0.25)
			(keepout
				(tracks not_allowed)
				(vias allowed)
				(pads allowed)
				(copperpour not_allowed)
				(footprints allowed)
			)
			(placement
				(enabled no)
				(sheetname "")
			)
			(fill
				(thermal_gap 0.5)
				(thermal_bridge_width 0.5)
				(island_removal_mode 0)
			)
			(polygon
				(pts
					(xy 386.04952 -111.2647) (xy 386.04952 -111.6457) (xy 386.22478 -111.6457) (xy 386.225034 -111.2647)
				)
			)
		)
		(zone
			(layer "B.Cu")
			(hatch none 0.5)
			(connect_pads
				(clearance 0)
			)
			(min_thickness 0.25)
			(keepout
				(tracks allowed)
				(vias not_allowed)
				(pads allowed)
				(copperpour not_allowed)
				(footprints allowed)
			)
			(placement
				(enabled no)
				(sheetname "")
			)
			(fill
				(thermal_gap 0.5)
				(thermal_bridge_width 0.5)
				(island_removal_mode 0)
			)
			(polygon
				(pts
					(xy 386.04952 -111.2647) (xy 386.04952 -111.6457) (xy 386.22478 -111.6457) (xy 386.225034 -111.2647)
				)
			)
		)
	)
)
